# SCM (Grand Teton) — schematic netlist excerpt (pin names and nets, part order shuffled) for the footprints in the layout excerpt that follows; sources: Cadence DE-HDL packaged netlist, KiCad conversion of 12092022_DA0F0TMDCD0_F0T_Management_Board_D_brd_V3_OCP.brd

R714  Q_RES  2K 1% CHIP  pkg 0402LF  page 27 : A = LPC_ESPI_SEL ; B = LPC_ESPI_SEL_R1
R444  Q_RES  33.2 1% CHIP  pkg 0402LF  page 13 : A = FM_ESPI_PLD_EN ; B = FM_ESPI_PLD_R1_EN

(kicad_pcb
	(version 20260206)
	(generator "pcbnew")
	(generator_version "10.0")
	(general
		(thickness 1.6)
		(legacy_teardrops no)
	)
	(paper "A4")
	(title_block
		(title "12092022_DA0F0TMDCD0_F0T_Management_Board_D_brd_V3_OCP.brd")
		(comment 1 "Grand Teton / footprints 1018-1020 of 1440")
	)
	(layers
		(0 "F.Cu" signal "TOP")
		(4 "In1.Cu" signal "GND")
		(6 "In2.Cu" signal "IN1")
		(8 "In3.Cu" signal "GND1")
		(10 "In4.Cu" signal "IN2")
		(12 "In5.Cu" signal "VCC")
		(14 "In6.Cu" signal "VCC1")
		(16 "In7.Cu" signal "IN3")
		(18 "In8.Cu" signal "GND2")
		(20 "In9.Cu" signal "IN4")
		(22 "In10.Cu" signal "GND3")
		(2 "B.Cu" signal "BOTTOM")
		(9 "F.Adhes" user "F.Adhesive")
		(11 "B.Adhes" user "B.Adhesive")
		(13 "F.Paste" user "Package Geometry/Pastemask Top")
		(15 "B.Paste" user "Package Geometry/Pastemask Bottom")
		(5 "F.SilkS" user "Ref Des/Silkscreen Top")
		(7 "B.SilkS" user "Ref Des/Silkscreen Bottom")
		(1 "F.Mask" user "Board Geometry/Soldermask Top")
		(3 "B.Mask" user "Board Geometry/Soldermask Bottom")
		(17 "Dwgs.User" user "User.Drawings")
		(19 "Cmts.User" user "User.Comments")
		(21 "Eco1.User" user "User.Eco1")
		(23 "Eco2.User" user "User.Eco2")
		(25 "Edge.Cuts" user "Board Geometry/Outline")
		(27 "Margin" user)
		(31 "F.CrtYd" user "Package Geometry/Place Bound Top")
		(29 "B.CrtYd" user "Package Geometry/Place Bound Bottom")
		(35 "F.Fab" user "Ref Des/Assembly Top")
		(33 "B.Fab" user "Ref Des/Assembly Bottom")
	)
	(footprint ""
		(layer "B.Cu")
		(at 74.095356 -99.906328)
		(property "Reference" "R714"
			(at 0 0 0)
			(layer "B.SilkS")
			(hide yes)
			(effects
				(font
					(size 1.27 1.27)
				)
				(justify mirror)
			)
		)
		(property "Value" ""
			(at 0 0 0)
			(layer "B.Fab")
			(effects
				(font
					(size 1.27 1.27)
				)
				(justify mirror)
			)
		)
		(duplicate_pad_numbers_are_jumpers no)
		(fp_line
			(start -0.7874 -0.4064)
			(end -0.7874 0.4064)
			(stroke
				(width 0.1524)
				(type default)
			)
			(layer "B.SilkS")
		)
		(fp_line
			(start -0.7874 0.4064)
			(end 0.7874 0.4064)
			(stroke
				(width 0.1524)
				(type default)
			)
			(layer "B.SilkS")
		)
		(fp_line
			(start 0.7874 -0.4064)
			(end -0.7874 -0.4064)
			(stroke
				(width 0.1524)
				(type default)
			)
			(layer "B.SilkS")
		)
		(fp_line
			(start 0.7874 0.4064)
			(end 0.7874 -0.4064)
			(stroke
				(width 0.1524)
				(type default)
			)
			(layer "B.SilkS")
		)
		(fp_line
			(start -0.67945 -0.3048)
			(end -0.67945 0.3048)
			(stroke
				(width 0.1)
				(type default)
			)
			(layer "B.Fab")
		)
		(fp_line
			(start -0.67945 0.3048)
			(end -0.120396 0.3048)
			(stroke
				(width 0.1)
				(type default)
			)
			(layer "B.Fab")
		)
		(fp_line
			(start -0.12065 -0.3048)
			(end -0.67945 -0.3048)
			(stroke
				(width 0.1)
				(type default)
			)
			(layer "B.Fab")
		)
		(fp_line
			(start -0.12065 -0.2794)
			(end -0.12065 -0.3048)
			(stroke
				(width 0.1)
				(type default)
			)
			(layer "B.Fab")
		)
		(fp_line
			(start -0.120396 0.2794)
			(end 0.12065 0.2794)
			(stroke
				(width 0.1)
				(type default)
			)
			(layer "B.Fab")
		)
		(fp_line
			(start -0.120396 0.3048)
			(end -0.120396 0.2794)
			(stroke
				(width 0.1)
				(type default)
			)
			(layer "B.Fab")
		)
		(fp_line
			(start 0.12065 -0.305054)
			(end 0.12065 -0.2794)
			(stroke
				(width 0.1)
				(type default)
			)
			(layer "B.Fab")
		)
		(fp_line
			(start 0.12065 -0.2794)
			(end -0.12065 -0.2794)
			(stroke
				(width 0.1)
				(type default)
			)
			(layer "B.Fab")
		)
		(fp_line
			(start 0.12065 0.2794)
			(end 0.12065 0.3048)
			(stroke
				(width 0.1)
				(type default)
			)
			(layer "B.Fab")
		)
		(fp_line
			(start 0.12065 0.3048)
			(end 0.67945 0.3048)
			(stroke
				(width 0.1)
				(type default)
			)
			(layer "B.Fab")
		)
		(fp_line
			(start 0.67945 -0.305054)
			(end 0.12065 -0.305054)
			(stroke
				(width 0.1)
				(type default)
			)
			(layer "B.Fab")
		)
		(fp_line
			(start 0.67945 0.3048)
			(end 0.67945 -0.305054)
			(stroke
				(width 0.1)
				(type default)
			)
			(layer "B.Fab")
		)
		(pad "1" smd circle
			(at 0.40005 0 180)
			(size 0 0)
			(layers "B.Cu" "B.Mask" "B.Paste")
			(net "LPC_ESPI_SEL")
		)
		(pad "2" smd circle
			(at -0.40005 0 180)
			(size 0 0)
			(layers "B.Cu" "B.Mask" "B.Paste")
			(net "LPC_ESPI_SEL_R1")
		)
	)
	(footprint ""
		(layer "B.Cu")
		(at 34.8996 -82.2452)
		(property "Reference" ""
			(at 0 0 0)
			(layer "B.SilkS")
			(hide yes)
			(effects
				(font
					(size 1.27 1.27)
				)
				(justify mirror)
			)
		)
		(property "Value" ""
			(at 0 0 0)
			(layer "B.Fab")
			(effects
				(font
					(size 1.27 1.27)
				)
				(justify mirror)
			)
		)
		(duplicate_pad_numbers_are_jumpers no)
		(pad "1" smd circle
			(at 0 0 180)
			(size 0.9906 0.9906)
			(layers "B.Cu" "B.Mask" "B.Paste")
			(net "Net_595")
		)
		(zone
			(layer "B.Cu")
			(hatch none 0.5)
			(connect_pads
				(clearance 0)
			)
			(min_thickness 0.25)
			(keepout
				(tracks not_allowed)
				(vias allowed)
				(pads allowed)
				(copperpour not_allowed)
				(footprints allowed)
			)
			(placement
				(enabled no)
				(sheetname "")
			)
			(fill
				(thermal_gap 0.5)
				(thermal_bridge_width 0.5)
				(island_removal_mode 0)
			)
			(polygon
				(pts
					(arc
						(start 36.5252 -82.2452)
						(mid 33.274 -82.2452)
						(end 36.5252 -82.2452)
					)
				)
			)
		)
	)
	(footprint ""
		(layer "B.Cu")
		(at 41.9608 -43.9928 180)
		(property "Reference" "R444"
			(at 0 0 0)
			(layer "B.SilkS")
			(hide yes)
			(effects
				(font
					(size 1.27 1.27)
				)
				(justify mirror)
			)
		)
		(property "Value" ""
			(at 0 0 0)
			(layer "B.Fab")
			(effects
				(font
					(size 1.27 1.27)
				)
				(justify mirror)
			)
		)
		(duplicate_pad_numbers_are_jumpers no)
		(fp_line
			(start 0.7874 0.4064)
			(end 0.7874 -0.4064)
			(stroke
				(width 0.1524)
				(type default)
			)
			(layer "B.SilkS")
		)
		(fp_line
			(start 0.7874 -0.4064)
			(end -0.7874 -0.4064)
			(stroke
				(width 0.1524)
				(type default)
			)
			(layer "B.SilkS")
		)
		(fp_line
			(start -0.7874 0.4064)
			(end 0.7874 0.4064)
			(stroke
				(width 0.1524)
				(type default)
			)
			(layer "B.SilkS")
		)
		(fp_line
			(start -0.7874 -0.4064)
			(end -0.7874 0.4064)
			(stroke
				(width 0.1524)
				(type default)
			)
			(layer "B.SilkS")
		)
		(fp_line
			(start 0.67945 0.3048)
			(end 0.67945 -0.305054)
			(stroke
				(width 0.1)
				(type default)
			)
			(layer "B.Fab")
		)
		(fp_line
			(start 0.67945 -0.305054)
			(end 0.12065 -0.305054)
			(stroke
				(width 0.1)
				(type default)
			)
			(layer "B.Fab")
		)
		(fp_line
			(start 0.12065 0.3048)
			(end 0.67945 0.3048)
			(stroke
				(width 0.1)
				(type default)
			)
			(layer "B.Fab")
		)
		(fp_line
			(start 0.12065 0.2794)
			(end 0.12065 0.3048)
			(stroke
				(width 0.1)
				(type default)
			)
			(layer "B.Fab")
		)
		(fp_line
			(start 0.12065 -0.2794)
			(end -0.12065 -0.2794)
			(stroke
				(width 0.1)
				(type default)
			)
			(layer "B.Fab")
		)
		(fp_line
			(start 0.12065 -0.305054)
			(end 0.12065 -0.2794)
			(stroke
				(width 0.1)
				(type default)
			)
			(layer "B.Fab")
		)
		(fp_line
			(start -0.120396 0.3048)
			(end -0.120396 0.2794)
			(stroke
				(width 0.1)
				(type default)
			)
			(layer "B.Fab")
		)
		(fp_line
			(start -0.120396 0.2794)
			(end 0.12065 0.2794)
			(stroke
				(width 0.1)
				(type default)
			)
			(layer "B.Fab")
		)
		(fp_line
			(start -0.12065 -0.2794)
			(end -0.12065 -0.3048)
			(stroke
				(width 0.1)
				(type default)
			)
			(layer "B.Fab")
		)
		(fp_line
			(start -0.12065 -0.3048)
			(end -0.67945 -0.3048)
			(stroke
				(width 0.1)
				(type default)
			)
			(layer "B.Fab")
		)
		(fp_line
			(start -0.67945 0.3048)
			(end -0.120396 0.3048)
			(stroke
				(width 0.1)
				(type default)
			)
			(layer "B.Fab")
		)
		(fp_line
			(start -0.67945 -0.3048)
			(end -0.67945 0.3048)
			(stroke
				(width 0.1)
				(type default)
			)
			(layer "B.Fab")
		)
		(pad "1" smd circle
			(at 0.40005 0)
			(size 0 0)
			(layers "B.Cu" "B.Mask" "B.Paste")
			(net "FM_ESPI_PLD_EN")
		)
		(pad "2" smd circle
			(at -0.40005 0)
			(size 0 0)
			(layers "B.Cu" "B.Mask" "B.Paste")
			(net "FM_ESPI_PLD_R1_EN")
		)
	)
)
